(kicad_pcb
	(version 20221018)
	(generator pcbnew)
	(general
    (thickness 1.62)
  )
	(paper "A4")
	(title_block
    (title "ECP5 - Datacenter Secure Control Module (DC-SCM)")
    (date "2024-07-01")
    (rev "1.2.1")
		(comment 9 "footprints 499-506 of 506")
	)
	(layers
    (0 "F.Cu" signal)
    (1 "In1.Cu" power)
    (2 "In2.Cu" signal)
    (3 "In3.Cu" power)
    (4 "In4.Cu" power)
    (5 "In5.Cu" signal)
    (6 "In6.Cu" power)
    (31 "B.Cu" signal)
    (32 "B.Adhes" user "B.Adhesive")
    (33 "F.Adhes" user "F.Adhesive")
    (34 "B.Paste" user)
    (35 "F.Paste" user)
    (36 "B.SilkS" user "B.Silkscreen")
    (37 "F.SilkS" user "F.Silkscreen")
    (38 "B.Mask" user)
    (39 "F.Mask" user)
    (40 "Dwgs.User" user "User.Drawings")
    (41 "Cmts.User" user "User.Comments")
    (42 "Eco1.User" user "User.Eco1")
    (43 "Eco2.User" user "User.Eco2")
    (44 "Edge.Cuts" user)
    (45 "Margin" user)
    (46 "B.CrtYd" user "B.Courtyard")
    (47 "F.CrtYd" user "F.Courtyard")
    (48 "B.Fab" user)
    (49 "F.Fab" user)
  )
	(footprint "antmicro-footprints:C_0402_1005Metric" (layer "B.Cu")
    (at 96.71 138.47 90)
    (descr "Capacitor SMD 0402")
    (tags "capacitor SMD 0402")
    (property "Author" "Antmicro")
    (property "Dielectric" "X5R")
    (property "License" "Apache-2.0")
    (property "MPN" "GRM155R61H104KE14D")
    (property "Manufacturer" "Murata")
    (property "Public" "False")
    (property "Sheetfile" "fpga-banks.kicad_sch")
    (property "Sheetname" "FPGA banks")
    (property "Val" "100n")
    (property "Voltage" "50V")
    (property "ki_description" "SMD Multilayer Ceramic Capacitor, 0.1 µF, 50 V, 0402 [1005 Metric], ± 10%, X5R, GRM Series")
    (property "ki_keywords" "0402, SMT, CAPACITOR, PASSIVE, CERAMIC, MLCC")
    (attr smd)
    (fp_text reference "C58" (at 0.045 -2.035 270) (layer "B.SilkS")
        (effects (font (size 0.7 0.7) (thickness 0.15)) (justify mirror))
    )
    (fp_text value "C_100n_0402" (at 0 -1.17 270) (layer "B.Fab")
        (effects (font (size 1 1) (thickness 0.15)) (justify mirror))
    )
    (fp_text user "License: Apache-2.0" (at -0.939 -5.799 270) (layer "B.Fab") hide
        (effects (font (size 0.7 0.7) (thickness 0.15)) (justify left bottom mirror))
    )
    (fp_text user "Author: Antmicro" (at -0.939 -3.399 270) (layer "B.Fab") hide
        (effects (font (size 0.7 0.7) (thickness 0.15)) (justify left bottom mirror))
    )
    (fp_text user "${REFERENCE}" (at 0 0 270) (layer "B.Fab")
        (effects (font (size 0.25 0.25) (thickness 0.04)) (justify mirror))
    )
    (fp_rect (start -0.925 0.47) (end 0.925 -0.47)
      (stroke (width 0.05) (type default)) (fill none) (layer "B.CrtYd"))
    (fp_line (start -0.494 -0.248) (end -0.494 0.25)
      (stroke (width 0.15) (type solid)) (layer "B.Fab"))
    (fp_line (start -0.494 0.25) (end 0.504 0.25)
      (stroke (width 0.15) (type solid)) (layer "B.Fab"))
    (fp_line (start 0.504 -0.248) (end -0.494 -0.248)
      (stroke (width 0.15) (type solid)) (layer "B.Fab"))
    (fp_line (start 0.504 0.25) (end 0.504 -0.248)
      (stroke (width 0.15) (type solid)) (layer "B.Fab"))
    (pad "1" smd roundrect (at -0.48 0 90) (size 0.59 0.64) (layers "B.Cu" "B.Paste" "B.Mask") (roundrect_rratio 0.25)
      (net 105 "PCIE_BMC_TX_DP") (pintype "passive"))
    (pad "2" smd roundrect (at 0.48 0 90) (size 0.59 0.64) (layers "B.Cu" "B.Paste" "B.Mask") (roundrect_rratio 0.25)
      (net 687 "/FPGA banks/PCIE_BMC_TX_C_DP") (pintype "passive"))
  )
	(footprint "antmicro-footprints:FB_0603_1608Metric" (layer "B.Cu")
    (at 108.75 92.75 90)
    (property "Author" "Antmicro")
    (property "Current" "")
    (property "License" "Apache-2.0")
    (property "MPN" "BLM18PG121SN1D")
    (property "Manufacturer" "Murata")
    (property "Public" "False")
    (property "Sheetfile" "ethernet.kicad_sch")
    (property "Sheetname" "Ethernet")
    (property "Val" "120Z/2A")
    (property "ki_description" "Ferrite Bead, 0603 [1608 Metric], 120 ohm, 2 A, BLM18P, 0.05 ohm, ± 25%, DC power line")
    (property "ki_keywords" "0603, SMT, FERRITE BEAD, PASSIVE")
    (attr smd)
    (fp_text reference "FB3" (at 0.435 1.56 90) (layer "B.SilkS")
        (effects (font (size 0.7 0.7) (thickness 0.127)) (justify mirror))
    )
    (fp_text value "FB_120Z_2A_Murata-BLM18PG_0603" (at 0 -1.9 90) (layer "B.Fab")
        (effects (font (size 1 1) (thickness 0.15)) (justify mirror))
    )
    (fp_text user "${REFERENCE}" (at -1.653 -4.6 270) (layer "B.Fab") hide
        (effects (font (size 0.7 0.7) (thickness 0.15)) (justify left bottom mirror))
    )
    (fp_text user "Author: Antmicro" (at -1.653 -3.162 270) (layer "B.Fab") hide
        (effects (font (size 0.7 0.7) (thickness 0.15)) (justify left bottom mirror))
    )
    (fp_text user "License: Apache-2.0" (at -1.653 -5.9 270) (layer "B.Fab") hide
        (effects (font (size 0.7 0.7) (thickness 0.15)) (justify left bottom mirror))
    )
    (fp_line (start -0.15 -0.4) (end 0.15 -0.4)
      (stroke (width 0.15) (type solid)) (layer "B.SilkS"))
    (fp_line (start -0.15 0.4) (end 0.15 0.4)
      (stroke (width 0.15) (type solid)) (layer "B.SilkS"))
    (fp_rect (start -1.25 0.65) (end 1.25 -0.65)
      (stroke (width 0.05) (type solid)) (fill none) (layer "B.CrtYd"))
    (fp_line (start -0.803 -0.406) (end -0.803 0.408)
      (stroke (width 0.15) (type solid)) (layer "B.Fab"))
    (fp_line (start 0.8 -0.406) (end -0.803 -0.406)
      (stroke (width 0.15) (type solid)) (layer "B.Fab"))
    (fp_line (start 0.8 0.408) (end -0.803 0.408)
      (stroke (width 0.15) (type solid)) (layer "B.Fab"))
    (fp_line (start 0.8 0.408) (end 0.8 -0.406)
      (stroke (width 0.15) (type solid)) (layer "B.Fab"))
    (pad "1" smd roundrect (at -0.7 0 90) (size 0.8 1) (layers "B.Cu" "B.Paste" "B.Mask") (roundrect_rratio 0.2)
      (net 10 "/Ethernet/AVDDL_PLL") (pintype "passive"))
    (pad "2" smd roundrect (at 0.7 0 90) (size 0.8 1) (layers "B.Cu" "B.Paste" "B.Mask") (roundrect_rratio 0.2)
      (net 211 "VCC1V2") (pintype "passive"))
  )
	(footprint "antmicro-footprints:R_0402_1005Metric" (layer "B.Cu")
    (at 94.55 98.125 180)
    (descr "Resistor SMD 0402")
    (tags "resistor SMD 0402")
    (property "Author" "Antmicro")
    (property "License" "Apache-2.0")
    (property "MPN" "CR0402-FX-4702GLF")
    (property "Manufacturer" "Bourns")
    (property "Public" "False")
    (property "Sheetfile" "interfaces.kicad_sch")
    (property "Sheetname" "Interfaces")
    (property "Tolerance" "1%")
    (property "Val" "47k")
    (property "ki_description" "SMD Chip Resistor, 47 kohm, ± 1%, 62.5 mW, 0402 [1005 Metric], Thick Film, General Purpose")
    (property "ki_keywords" "0402, SMT, RESISTOR, PASSIVE")
    (attr smd)
    (fp_text reference "R60" (at 0 -7.275) (layer "B.SilkS")
        (effects (font (size 0.7 0.7) (thickness 0.127)) (justify mirror))
    )
    (fp_text value "R_47k_0402" (at 0 -1.17) (layer "B.Fab")
        (effects (font (size 1 1) (thickness 0.15)) (justify mirror))
    )
    (fp_text user "Author: Antmicro" (at -0.95 -4.169) (layer "B.Fab") hide
        (effects (font (size 0.7 0.7) (thickness 0.15)) (justify left bottom mirror))
    )
    (fp_text user "${REFERENCE}" (at 0 0) (layer "B.Fab")
        (effects (font (size 0.25 0.25) (thickness 0.04)) (justify mirror))
    )
    (fp_text user "License: Apache-2.0" (at -0.95 -5.169) (layer "B.Fab") hide
        (effects (font (size 0.7 0.7) (thickness 0.15)) (justify left bottom mirror))
    )
    (fp_rect (start -0.925 0.47) (end 0.925 -0.47)
      (stroke (width 0.05) (type default)) (fill none) (layer "B.CrtYd"))
    (fp_rect (start -0.5 0.25) (end 0.5 -0.25)
      (stroke (width 0.15) (type solid)) (fill none) (layer "B.Fab"))
    (pad "1" smd roundrect (at -0.48 0 180) (size 0.59 0.64) (layers "B.Cu" "B.Paste" "B.Mask") (roundrect_rratio 0.25)
      (net 2 "VCC3V3") (pintype "passive"))
    (pad "2" smd roundrect (at 0.48 0 180) (size 0.59 0.64) (layers "B.Cu" "B.Paste" "B.Mask") (roundrect_rratio 0.25)
      (net 287 "MMC_CMD") (pintype "passive"))
  )
	(footprint "antmicro-footprints:R_0402_1005Metric" (layer "B.Cu")
    (at 94.565 97.1)
    (descr "Resistor SMD 0402")
    (tags "resistor SMD 0402")
    (property "Author" "Antmicro")
    (property "License" "Apache-2.0")
    (property "MPN" "CR0402-FX-22R0GLF")
    (property "Manufacturer" "Bourns")
    (property "Public" "False")
    (property "Sheetfile" "interfaces.kicad_sch")
    (property "Sheetname" "Interfaces")
    (property "Tolerance" "1%")
    (property "Val" "22R")
    (property "ki_description" "SMD Chip Resistor, 22 ohm, ± 1%, 62.5 mW, 0402 [1005 Metric], Thick Film, General Purpose")
    (property "ki_keywords" "0402, SMT, RESISTOR, PASSIVE")
    (attr smd)
    (fp_text reference "R14" (at -0.015 7.375) (layer "B.SilkS")
        (effects (font (size 0.7 0.7) (thickness 0.127)) (justify mirror))
    )
    (fp_text value "R_22R_0402" (at 0 -1.17) (layer "B.Fab")
        (effects (font (size 1 1) (thickness 0.15)) (justify mirror))
    )
    (fp_text user "Author: Antmicro" (at -0.95 -4.169 180) (layer "B.Fab") hide
        (effects (font (size 0.7 0.7) (thickness 0.15)) (justify left bottom mirror))
    )
    (fp_text user "${REFERENCE}" (at 0 0) (layer "B.Fab")
        (effects (font (size 0.25 0.25) (thickness 0.04)) (justify mirror))
    )
    (fp_text user "License: Apache-2.0" (at -0.95 -5.169 180) (layer "B.Fab") hide
        (effects (font (size 0.7 0.7) (thickness 0.15)) (justify left bottom mirror))
    )
    (fp_rect (start -0.925 0.47) (end 0.925 -0.47)
      (stroke (width 0.05) (type default)) (fill none) (layer "B.CrtYd"))
    (fp_rect (start -0.5 0.25) (end 0.5 -0.25)
      (stroke (width 0.15) (type solid)) (fill none) (layer "B.Fab"))
    (pad "1" smd roundrect (at -0.48 0) (size 0.59 0.64) (layers "B.Cu" "B.Paste" "B.Mask") (roundrect_rratio 0.25)
      (net 403 "Net-(U6-CLK)") (pintype "passive"))
    (pad "2" smd roundrect (at 0.48 0) (size 0.59 0.64) (layers "B.Cu" "B.Paste" "B.Mask") (roundrect_rratio 0.25)
      (net 288 "MMC_CLK") (pintype "passive"))
  )
	(footprint "antmicro-footprints:C_0402_1005Metric" (layer "B.Cu")
    (at 97.3 95.2)
    (descr "Capacitor SMD 0402")
    (tags "capacitor SMD 0402")
    (property "Author" "Antmicro")
    (property "Dielectric" "X7R")
    (property "License" "Apache-2.0")
    (property "MPN" "GRM155R71H103KA88D")
    (property "Manufacturer" "Murata")
    (property "Public" "False")
    (property "Sheetfile" "ethernet.kicad_sch")
    (property "Sheetname" "Ethernet")
    (property "Val" "10n")
    (property "Voltage" "50V")
    (property "ki_description" "SMD Multilayer Ceramic Capacitor, 10000 pF, 50 V, 0402 [1005 Metric], ± 10%, X7R, GRM Series")
    (property "ki_keywords" "0402, SMT, CAPACITOR, PASSIVE")
    (attr smd)
    (fp_text reference "C11" (at 0.08 1.145) (layer "B.SilkS")
        (effects (font (size 0.7 0.7) (thickness 0.127)) (justify mirror))
    )
    (fp_text value "C_10n_0402" (at 0 -1.17) (layer "B.Fab")
        (effects (font (size 1 1) (thickness 0.15)) (justify mirror))
    )
    (fp_text user "${REFERENCE}" (at 0 0) (layer "B.Fab")
        (effects (font (size 0.25 0.25) (thickness 0.04)) (justify mirror))
    )
    (fp_text user "License: Apache-2.0" (at -0.939 -5.799 180) (layer "B.Fab") hide
        (effects (font (size 0.7 0.7) (thickness 0.15)) (justify left bottom mirror))
    )
    (fp_text user "Author: Antmicro" (at -0.939 -3.399 180) (layer "B.Fab") hide
        (effects (font (size 0.7 0.7) (thickness 0.15)) (justify left bottom mirror))
    )
    (fp_rect (start -0.925 0.47) (end 0.925 -0.47)
      (stroke (width 0.05) (type default)) (fill none) (layer "B.CrtYd"))
    (fp_line (start -0.494 -0.248) (end -0.494 0.25)
      (stroke (width 0.15) (type solid)) (layer "B.Fab"))
    (fp_line (start -0.494 0.25) (end 0.504 0.25)
      (stroke (width 0.15) (type solid)) (layer "B.Fab"))
    (fp_line (start 0.504 -0.248) (end -0.494 -0.248)
      (stroke (width 0.15) (type solid)) (layer "B.Fab"))
    (fp_line (start 0.504 0.25) (end 0.504 -0.248)
      (stroke (width 0.15) (type solid)) (layer "B.Fab"))
    (pad "1" smd roundrect (at -0.48 0) (size 0.59 0.64) (layers "B.Cu" "B.Paste" "B.Mask") (roundrect_rratio 0.25)
      (net 1 "GND") (pintype "passive"))
    (pad "2" smd roundrect (at 0.48 0) (size 0.59 0.64) (layers "B.Cu" "B.Paste" "B.Mask") (roundrect_rratio 0.25)
      (net 2 "VCC3V3") (pintype "passive"))
  )
	(footprint "antmicro-footprints:C_0402_1005Metric" (layer "B.Cu")
    (at 100.1 96.95 180)
    (descr "Capacitor SMD 0402")
    (tags "capacitor SMD 0402")
    (property "Author" "Antmicro")
    (property "Dielectric" "X7R")
    (property "License" "Apache-2.0")
    (property "MPN" "GRM155R71H103KA88D")
    (property "Manufacturer" "Murata")
    (property "Public" "False")
    (property "Sheetfile" "ethernet.kicad_sch")
    (property "Sheetname" "Ethernet")
    (property "Val" "10n")
    (property "Voltage" "50V")
    (property "ki_description" "SMD Multilayer Ceramic Capacitor, 10000 pF, 50 V, 0402 [1005 Metric], ± 10%, X7R, GRM Series")
    (property "ki_keywords" "0402, SMT, CAPACITOR, PASSIVE")
    (attr smd)
    (fp_text reference "C9" (at 1.61 -0.345) (layer "B.SilkS")
        (effects (font (size 0.7 0.7) (thickness 0.127)) (justify mirror))
    )
    (fp_text value "C_10n_0402" (at 0 -1.17) (layer "B.Fab")
        (effects (font (size 1 1) (thickness 0.15)) (justify mirror))
    )
    (fp_text user "${REFERENCE}" (at 0 0) (layer "B.Fab")
        (effects (font (size 0.25 0.25) (thickness 0.04)) (justify mirror))
    )
    (fp_text user "License: Apache-2.0" (at -0.939 -5.799) (layer "B.Fab") hide
        (effects (font (size 0.7 0.7) (thickness 0.15)) (justify left bottom mirror))
    )
    (fp_text user "Author: Antmicro" (at -0.939 -3.399) (layer "B.Fab") hide
        (effects (font (size 0.7 0.7) (thickness 0.15)) (justify left bottom mirror))
    )
    (fp_rect (start -0.925 0.47) (end 0.925 -0.47)
      (stroke (width 0.05) (type default)) (fill none) (layer "B.CrtYd"))
    (fp_line (start -0.494 -0.248) (end -0.494 0.25)
      (stroke (width 0.15) (type solid)) (layer "B.Fab"))
    (fp_line (start -0.494 0.25) (end 0.504 0.25)
      (stroke (width 0.15) (type solid)) (layer "B.Fab"))
    (fp_line (start 0.504 -0.248) (end -0.494 -0.248)
      (stroke (width 0.15) (type solid)) (layer "B.Fab"))
    (fp_line (start 0.504 0.25) (end 0.504 -0.248)
      (stroke (width 0.15) (type solid)) (layer "B.Fab"))
    (pad "1" smd roundrect (at -0.48 0 180) (size 0.59 0.64) (layers "B.Cu" "B.Paste" "B.Mask") (roundrect_rratio 0.25)
      (net 1 "GND") (pintype "passive"))
    (pad "2" smd roundrect (at 0.48 0 180) (size 0.59 0.64) (layers "B.Cu" "B.Paste" "B.Mask") (roundrect_rratio 0.25)
      (net 211 "VCC1V2") (pintype "passive"))
  )
	(footprint "antmicro-footprints:C_0402_1005Metric" (layer "B.Cu")
    (at 97.3 94.15)
    (descr "Capacitor SMD 0402")
    (tags "capacitor SMD 0402")
    (property "Author" "Antmicro")
    (property "Dielectric" "X7R")
    (property "License" "Apache-2.0")
    (property "MPN" "GRM155R71H103KA88D")
    (property "Manufacturer" "Murata")
    (property "Public" "False")
    (property "Sheetfile" "ethernet.kicad_sch")
    (property "Sheetname" "Ethernet")
    (property "Val" "10n")
    (property "Voltage" "50V")
    (property "ki_description" "SMD Multilayer Ceramic Capacitor, 10000 pF, 50 V, 0402 [1005 Metric], ± 10%, X7R, GRM Series")
    (property "ki_keywords" "0402, SMT, CAPACITOR, PASSIVE")
    (attr smd)
    (fp_text reference "C5" (at -0.47 -0.885) (layer "B.SilkS")
        (effects (font (size 0.7 0.7) (thickness 0.127)) (justify mirror))
    )
    (fp_text value "C_10n_0402" (at 0 -1.17) (layer "B.Fab")
        (effects (font (size 1 1) (thickness 0.15)) (justify mirror))
    )
    (fp_text user "Author: Antmicro" (at -0.939 -3.399 180) (layer "B.Fab") hide
        (effects (font (size 0.7 0.7) (thickness 0.15)) (justify left bottom mirror))
    )
    (fp_text user "${REFERENCE}" (at 0 0) (layer "B.Fab")
        (effects (font (size 0.25 0.25) (thickness 0.04)) (justify mirror))
    )
    (fp_text user "License: Apache-2.0" (at -0.939 -5.799 180) (layer "B.Fab") hide
        (effects (font (size 0.7 0.7) (thickness 0.15)) (justify left bottom mirror))
    )
    (fp_rect (start -0.925 0.47) (end 0.925 -0.47)
      (stroke (width 0.05) (type default)) (fill none) (layer "B.CrtYd"))
    (fp_line (start -0.494 -0.248) (end -0.494 0.25)
      (stroke (width 0.15) (type solid)) (layer "B.Fab"))
    (fp_line (start -0.494 0.25) (end 0.504 0.25)
      (stroke (width 0.15) (type solid)) (layer "B.Fab"))
    (fp_line (start 0.504 -0.248) (end -0.494 -0.248)
      (stroke (width 0.15) (type solid)) (layer "B.Fab"))
    (fp_line (start 0.504 0.25) (end 0.504 -0.248)
      (stroke (width 0.15) (type solid)) (layer "B.Fab"))
    (pad "1" smd roundrect (at -0.48 0) (size 0.59 0.64) (layers "B.Cu" "B.Paste" "B.Mask") (roundrect_rratio 0.25)
      (net 1 "GND") (pintype "passive"))
    (pad "2" smd roundrect (at 0.48 0) (size 0.59 0.64) (layers "B.Cu" "B.Paste" "B.Mask") (roundrect_rratio 0.25)
      (net 211 "VCC1V2") (pintype "passive"))
  )
	(footprint "antmicro-footprints:C_0402_1005Metric" (layer "B.Cu")
    (at 100.1 97.95 180)
    (descr "Capacitor SMD 0402")
    (tags "capacitor SMD 0402")
    (property "Author" "Antmicro")
    (property "Dielectric" "")
    (property "License" "Apache-2.0")
    (property "MPN" "C1005X5R1E474M050BB")
    (property "Manufacturer" "TDK")
    (property "Public" "False")
    (property "Sheetfile" "ethernet.kicad_sch")
    (property "Sheetname" "Ethernet")
    (property "Val" "470n")
    (property "Voltage" "")
    (property "ki_description" "SMD Multilayer Ceramic Capacitor, 0.47 µF, 25 V, 0402 [1005 Metric], ± 20%, X5R, C")
    (property "ki_keywords" "0402, SMT, CAPACITOR, PASSIVE, CERAMIC, MLCC")
    (attr smd)
    (fp_text reference "C4" (at 1.7 -0.225) (layer "B.SilkS")
        (effects (font (size 0.7 0.7) (thickness 0.127)) (justify mirror))
    )
    (fp_text value "C_470n_0402" (at 0 -1.17) (layer "B.Fab")
        (effects (font (size 1 1) (thickness 0.15)) (justify mirror))
    )
    (fp_text user "${REFERENCE}" (at 0 0) (layer "B.Fab")
        (effects (font (size 0.25 0.25) (thickness 0.04)) (justify mirror))
    )
    (fp_text user "Author: Antmicro" (at -0.939 -3.399) (layer "B.Fab") hide
        (effects (font (size 0.7 0.7) (thickness 0.15)) (justify left bottom mirror))
    )
    (fp_text user "License: Apache-2.0" (at -0.939 -5.799) (layer "B.Fab") hide
        (effects (font (size 0.7 0.7) (thickness 0.15)) (justify left bottom mirror))
    )
    (fp_rect (start -0.925 0.47) (end 0.925 -0.47)
      (stroke (width 0.05) (type default)) (fill none) (layer "B.CrtYd"))
    (fp_line (start -0.494 -0.248) (end -0.494 0.25)
      (stroke (width 0.15) (type solid)) (layer "B.Fab"))
    (fp_line (start -0.494 0.25) (end 0.504 0.25)
      (stroke (width 0.15) (type solid)) (layer "B.Fab"))
    (fp_line (start 0.504 -0.248) (end -0.494 -0.248)
      (stroke (width 0.15) (type solid)) (layer "B.Fab"))
    (fp_line (start 0.504 0.25) (end 0.504 -0.248)
      (stroke (width 0.15) (type solid)) (layer "B.Fab"))
    (pad "1" smd roundrect (at -0.48 0 180) (size 0.59 0.64) (layers "B.Cu" "B.Paste" "B.Mask") (roundrect_rratio 0.25)
      (net 1 "GND") (pintype "passive"))
    (pad "2" smd roundrect (at 0.48 0 180) (size 0.59 0.64) (layers "B.Cu" "B.Paste" "B.Mask") (roundrect_rratio 0.25)
      (net 211 "VCC1V2") (pintype "passive"))
  )
)
